(kicad_pcb
	(version 20260206)
	(generator "pcbnew")
	(generator_version "10.0")
	(general
		(thickness 1.6)
		(legacy_teardrops no)
	)
	(paper "A4")
	(title_block
		(title "Wiwynn_Tioga_Pass_MB.brd")
		(comment 1 "Tioga Pass / footprints 4747-4753 of 4770")
	)
	(layers
		(0 "F.Cu" signal "TOP")
		(4 "In1.Cu" signal "L2GND")
		(6 "In2.Cu" signal "L3")
		(8 "In3.Cu" signal "L4GND")
		(10 "In4.Cu" signal "L5")
		(12 "In5.Cu" signal "L6GND")
		(14 "In6.Cu" signal "L7VCC")
		(16 "In7.Cu" signal "L8VCC")
		(18 "In8.Cu" signal "L9GND")
		(20 "In9.Cu" signal "L10")
		(22 "In10.Cu" signal "L11GND")
		(24 "In11.Cu" signal "L12")
		(26 "In12.Cu" signal "L13GND")
		(2 "B.Cu" signal "BOTTOM")
		(9 "F.Adhes" user "F.Adhesive")
		(11 "B.Adhes" user "B.Adhesive")
		(13 "F.Paste" user "Package Geometry/Pastemask Top")
		(15 "B.Paste" user "Package Geometry/Pastemask Bottom")
		(5 "F.SilkS" user "Ref Des/Silkscreen Top")
		(7 "B.SilkS" user "Ref Des/Silkscreen Bottom")
		(1 "F.Mask" user "Board Geometry/Soldermask Top")
		(3 "B.Mask" user "Board Geometry/Soldermask Bottom")
		(17 "Dwgs.User" user "User.Drawings")
		(19 "Cmts.User" user "User.Comments")
		(21 "Eco1.User" user "User.Eco1")
		(23 "Eco2.User" user "User.Eco2")
		(25 "Edge.Cuts" user "Board Geometry/Outline")
		(27 "Margin" user)
		(31 "F.CrtYd" user "Package Geometry/Place Bound Top")
		(29 "B.CrtYd" user "Package Geometry/Place Bound Bottom")
		(35 "F.Fab" user "Ref Des/Assembly Top")
		(33 "B.Fab" user "Ref Des/Assembly Bottom")
	)
	(footprint ""
		(layer "B.Cu")
		(at 259.5372 -135.376412 90)
		(property "Reference" "C5M8"
			(at 0 0 90)
			(layer "B.SilkS")
			(hide yes)
			(effects
				(font
					(size 1.27 1.27)
				)
				(justify mirror)
			)
		)
		(property "Value" ""
			(at 0 0 90)
			(layer "B.Fab")
			(effects
				(font
					(size 1.27 1.27)
				)
				(justify mirror)
			)
		)
		(duplicate_pad_numbers_are_jumpers no)
		(fp_rect
			(start -0.7239 -0.2159)
			(end 0.7239 1.9939)
			(stroke
				(width 0)
				(type default)
			)
			(fill no)
			(layer "B.CrtYd")
		)
		(fp_line
			(start 0.7239 -0.2159)
			(end 0.7239 1.9939)
			(stroke
				(width 0.1)
				(type default)
			)
			(layer "B.Fab")
		)
		(fp_line
			(start -0.7239 -0.2159)
			(end 0.7239 -0.2159)
			(stroke
				(width 0.1)
				(type default)
			)
			(layer "B.Fab")
		)
		(fp_line
			(start 0.7239 1.9939)
			(end -0.7239 1.9939)
			(stroke
				(width 0.1)
				(type default)
			)
			(layer "B.Fab")
		)
		(fp_line
			(start -0.7239 1.9939)
			(end -0.7239 -0.2159)
			(stroke
				(width 0.1)
				(type default)
			)
			(layer "B.Fab")
		)
		(pad "1" smd rect
			(at 0 0 270)
			(size 1.27 1.016)
			(layers "B.Cu" "B.Mask" "B.Paste")
			(net "PVDDQ_DEF")
		)
		(pad "2" smd rect
			(at 0 1.778 270)
			(size 1.27 1.016)
			(layers "B.Cu" "B.Mask" "B.Paste")
			(net "GND")
		)
		(zone
			(layer "B.Cu")
			(hatch none 0.5)
			(connect_pads
				(clearance 0)
			)
			(min_thickness 0.25)
			(keepout
				(tracks not_allowed)
				(vias allowed)
				(pads allowed)
				(copperpour not_allowed)
				(footprints allowed)
			)
			(placement
				(enabled no)
				(sheetname "")
			)
			(fill
				(thermal_gap 0.5)
				(thermal_bridge_width 0.5)
				(island_removal_mode 0)
			)
			(polygon
				(pts
					(xy 260.0452 -134.741412) (xy 260.8072 -134.741412) (xy 260.8072 -136.011412) (xy 260.0452 -136.011412)
				)
			)
		)
	)
	(footprint ""
		(layer "B.Cu")
		(at 439.4073 -141.097 180)
		(property "Reference" "C25W95"
			(at 0.8382 -0.67818 180)
			(unlocked yes)
			(layer "B.SilkS")
			(effects
				(font
					(size 0.4064 0.254)
					(thickness 0.1524)
				)
				(justify left mirror)
			)
		)
		(property "Value" ""
			(at 0 0 0)
			(layer "B.Fab")
			(effects
				(font
					(size 1.27 1.27)
				)
				(justify mirror)
			)
		)
		(duplicate_pad_numbers_are_jumpers no)
		(fp_poly
			(pts
				(xy -0.3048 -0.1016) (xy -0.3048 0.9906) (xy 0.3048 0.9906) (xy 0.3048 -0.1016)
			)
			(stroke
				(width 0)
				(type default)
			)
			(fill no)
			(layer "B.CrtYd")
		)
		(fp_line
			(start 0.3048 0.9906)
			(end -0.3048 0.9906)
			(stroke
				(width 0.1)
				(type default)
			)
			(layer "B.Fab")
		)
		(fp_line
			(start 0.3048 -0.1016)
			(end 0.3048 0.9906)
			(stroke
				(width 0.1)
				(type default)
			)
			(layer "B.Fab")
		)
		(fp_line
			(start -0.3048 0.9906)
			(end -0.3048 -0.1016)
			(stroke
				(width 0.1)
				(type default)
			)
			(layer "B.Fab")
		)
		(fp_line
			(start -0.3048 -0.1016)
			(end 0.3048 -0.1016)
			(stroke
				(width 0.1)
				(type default)
			)
			(layer "B.Fab")
		)
		(pad "1" smd rect
			(at 0 0)
			(size 0.508 0.508)
			(layers "B.Cu" "B.Mask" "B.Paste")
			(net "P3V3_STBY")
		)
		(pad "2" smd rect
			(at 0 0.889)
			(size 0.508 0.508)
			(layers "B.Cu" "B.Mask" "B.Paste")
			(net "GND")
		)
		(zone
			(layer "B.Cu")
			(hatch none 0.5)
			(connect_pads
				(clearance 0)
			)
			(min_thickness 0.25)
			(keepout
				(tracks not_allowed)
				(vias allowed)
				(pads allowed)
				(copperpour not_allowed)
				(footprints allowed)
			)
			(placement
				(enabled no)
				(sheetname "")
			)
			(fill
				(thermal_gap 0.5)
				(thermal_bridge_width 0.5)
				(island_removal_mode 0)
			)
			(polygon
				(pts
					(xy 439.1533 -141.732) (xy 439.6613 -141.732) (xy 439.6613 -141.351) (xy 439.1533 -141.351)
				)
			)
		)
		(zone
			(layer "B.Cu")
			(hatch none 0.5)
			(connect_pads
				(clearance 0)
			)
			(min_thickness 0.25)
			(keepout
				(tracks allowed)
				(vias not_allowed)
				(pads allowed)
				(copperpour not_allowed)
				(footprints allowed)
			)
			(placement
				(enabled no)
				(sheetname "")
			)
			(fill
				(thermal_gap 0.5)
				(thermal_bridge_width 0.5)
				(island_removal_mode 0)
			)
			(polygon
				(pts
					(xy 439.1533 -141.351) (xy 439.6613 -141.351) (xy 439.6613 -141.732) (xy 439.1533 -141.732)
				)
			)
		)
	)
	(footprint ""
		(layer "B.Cu")
		(at 386.93725 -111.05515 180)
		(property "Reference" "C3N5"
			(at 0 0 0)
			(layer "B.SilkS")
			(hide yes)
			(effects
				(font
					(size 1.27 1.27)
				)
				(justify mirror)
			)
		)
		(property "Value" ""
			(at 0 0 0)
			(layer "B.Fab")
			(effects
				(font
					(size 1.27 1.27)
				)
				(justify mirror)
			)
		)
		(duplicate_pad_numbers_are_jumpers no)
		(fp_rect
			(start 0.2794 0.9144)
			(end -0.2794 -0.1143)
			(stroke
				(width 0)
				(type default)
			)
			(fill no)
			(layer "B.CrtYd")
		)
		(fp_line
			(start 0.2794 0.9144)
			(end 0.2794 -0.1143)
			(stroke
				(width 0.1)
				(type default)
			)
			(layer "B.Fab")
		)
		(fp_line
			(start 0.2794 -0.1143)
			(end -0.2794 -0.1143)
			(stroke
				(width 0.1)
				(type default)
			)
			(layer "B.Fab")
		)
		(fp_line
			(start -0.2794 0.9144)
			(end 0.2794 0.9144)
			(stroke
				(width 0.1)
				(type default)
			)
			(layer "B.Fab")
		)
		(fp_line
			(start -0.2794 -0.1143)
			(end -0.2794 0.9144)
			(stroke
				(width 0.1)
				(type default)
			)
			(layer "B.Fab")
		)
		(pad "1" smd custom
			(at 0 0 90)
			(size 0.10414 0.10414)
			(layers "B.Cu" "B.Mask" "B.Paste")
			(net "PVNN_PCH_STBY")
			(options
				(clearance outline)
				(anchor circle)
			)
			(primitives
				(gr_poly
					(pts
						(xy -0.20828 -0.08636) (xy -0.20828 0.08636) (xy -0.08636 0.20828) (xy 0.086614 0.20828) (xy 0.20828 0.086614)
						(xy 0.20828 -0.08636) (xy 0.08636 -0.20828) (xy -0.08636 -0.20828)
					)
					(width 0)
					(fill yes)
				)
			)
		)
		(pad "2" smd custom
			(at 0 0.8001 90)
			(size 0.10414 0.10414)
			(layers "B.Cu" "B.Mask" "B.Paste")
			(net "GND")
			(options
				(clearance outline)
				(anchor circle)
			)
			(primitives
				(gr_poly
					(pts
						(xy -0.20828 -0.08636) (xy -0.20828 0.08636) (xy -0.08636 0.20828) (xy 0.086614 0.20828) (xy 0.20828 0.086614)
						(xy 0.20828 -0.08636) (xy 0.08636 -0.20828) (xy -0.08636 -0.20828)
					)
					(width 0)
					(fill yes)
				)
			)
		)
		(zone
			(layer "B.Cu")
			(hatch none 0.5)
			(connect_pads
				(clearance 0)
			)
			(min_thickness 0.25)
			(keepout
				(tracks allowed)
				(vias not_allowed)
				(pads allowed)
				(copperpour not_allowed)
				(footprints allowed)
			)
			(placement
				(enabled no)
				(sheetname "")
			)
			(fill
				(thermal_gap 0.5)
				(thermal_bridge_width 0.5)
				(island_removal_mode 0)
			)
			(polygon
				(pts
					(xy 386.84962 -111.2647) (xy 386.84962 -111.6457) (xy 387.02488 -111.6457) (xy 387.025134 -111.2647)
				)
			)
		)
		(zone
			(layer "B.Cu")
			(hatch none 0.5)
			(connect_pads
				(clearance 0)
			)
			(min_thickness 0.25)
			(keepout
				(tracks not_allowed)
				(vias allowed)
				(pads allowed)
				(copperpour not_allowed)
				(footprints allowed)
			)
			(placement
				(enabled no)
				(sheetname "")
			)
			(fill
				(thermal_gap 0.5)
				(thermal_bridge_width 0.5)
				(island_removal_mode 0)
			)
			(polygon
				(pts
					(xy 386.84962 -111.2647) (xy 386.84962 -111.6457) (xy 387.02488 -111.6457) (xy 387.025134 -111.2647)
				)
			)
		)
	)
	(footprint ""
		(layer "B.Cu")
		(at 381.508 -87.3125 180)
		(property "Reference" "R7D4"
			(at 0 0 0)
			(layer "B.SilkS")
			(hide yes)
			(effects
				(font
					(size 1.27 1.27)
				)
				(justify mirror)
			)
		)
		(property "Value" ""
			(at 0 0 0)
			(layer "B.Fab")
			(effects
				(font
					(size 1.27 1.27)
				)
				(justify mirror)
			)
		)
		(duplicate_pad_numbers_are_jumpers no)
		(fp_poly
			(pts
				(xy 0.2794 -0.1016) (xy -0.2794 -0.1016) (xy -0.2794 0.9906) (xy 0.2794 0.9906)
			)
			(stroke
				(width 0)
				(type default)
			)
			(fill no)
			(layer "B.CrtYd")
		)
		(fp_line
			(start 0.2794 0.9906)
			(end -0.2794 0.9906)
			(stroke
				(width 0.1)
				(type default)
			)
			(layer "B.Fab")
		)
		(fp_line
			(start 0.2794 -0.1016)
			(end 0.2794 0.9906)
			(stroke
				(width 0.1)
				(type default)
			)
			(layer "B.Fab")
		)
		(fp_line
			(start -0.2794 0.9906)
			(end -0.2794 -0.1016)
			(stroke
				(width 0.1)
				(type default)
			)
			(layer "B.Fab")
		)
		(fp_line
			(start -0.2794 -0.1016)
			(end 0.2794 -0.1016)
			(stroke
				(width 0.1)
				(type default)
			)
			(layer "B.Fab")
		)
		(pad "1" smd rect
			(at 0 0)
			(size 0.508 0.508)
			(layers "B.Cu" "B.Mask" "B.Paste")
			(net "P3V3_STBY")
		)
		(pad "2" smd rect
			(at 0 0.889)
			(size 0.508 0.508)
			(layers "B.Cu" "B.Mask" "B.Paste")
			(net "PU_IRQ_PCH_SCI_WHEA_N")
		)
		(zone
			(layer "B.Cu")
			(hatch none 0.5)
			(connect_pads
				(clearance 0)
			)
			(min_thickness 0.25)
			(keepout
				(tracks not_allowed)
				(vias allowed)
				(pads allowed)
				(copperpour not_allowed)
				(footprints allowed)
			)
			(placement
				(enabled no)
				(sheetname "")
			)
			(fill
				(thermal_gap 0.5)
				(thermal_bridge_width 0.5)
				(island_removal_mode 0)
			)
			(polygon
				(pts
					(xy 381.254 -87.9475) (xy 381.762 -87.9475) (xy 381.762 -87.5665) (xy 381.254 -87.5665)
				)
			)
		)
		(zone
			(layer "B.Cu")
			(hatch none 0.5)
			(connect_pads
				(clearance 0)
			)
			(min_thickness 0.25)
			(keepout
				(tracks allowed)
				(vias not_allowed)
				(pads allowed)
				(copperpour not_allowed)
				(footprints allowed)
			)
			(placement
				(enabled no)
				(sheetname "")
			)
			(fill
				(thermal_gap 0.5)
				(thermal_bridge_width 0.5)
				(island_removal_mode 0)
			)
			(polygon
				(pts
					(xy 381.254 -87.5665) (xy 381.762 -87.5665) (xy 381.762 -87.9475) (xy 381.254 -87.9475)
				)
			)
		)
	)
	(footprint ""
		(layer "B.Cu")
		(at 381.4826 -3.185414 90)
		(property "Reference" "R8W15"
			(at 0.8382 -0.67818 90)
			(unlocked yes)
			(layer "B.SilkS")
			(effects
				(font
					(size 0.4064 0.254)
					(thickness 0.1524)
				)
				(justify left mirror)
			)
		)
		(property "Value" ""
			(at 0 0 90)
			(layer "B.Fab")
			(effects
				(font
					(size 1.27 1.27)
				)
				(justify mirror)
			)
		)
		(duplicate_pad_numbers_are_jumpers no)
		(fp_poly
			(pts
				(xy 0.2794 -0.1016) (xy -0.2794 -0.1016) (xy -0.2794 0.9906) (xy 0.2794 0.9906)
			)
			(stroke
				(width 0)
				(type default)
			)
			(fill no)
			(layer "B.CrtYd")
		)
		(fp_line
			(start 0.2794 -0.1016)
			(end 0.2794 0.9906)
			(stroke
				(width 0.1)
				(type default)
			)
			(layer "B.Fab")
		)
		(fp_line
			(start -0.2794 -0.1016)
			(end 0.2794 -0.1016)
			(stroke
				(width 0.1)
				(type default)
			)
			(layer "B.Fab")
		)
		(fp_line
			(start 0.2794 0.9906)
			(end -0.2794 0.9906)
			(stroke
				(width 0.1)
				(type default)
			)
			(layer "B.Fab")
		)
		(fp_line
			(start -0.2794 0.9906)
			(end -0.2794 -0.1016)
			(stroke
				(width 0.1)
				(type default)
			)
			(layer "B.Fab")
		)
		(pad "1" smd rect
			(at 0 0 270)
			(size 0.508 0.508)
			(layers "B.Cu" "B.Mask" "B.Paste")
			(net "P3V3_STBY")
		)
		(pad "2" smd rect
			(at 0 0.889 270)
			(size 0.508 0.508)
			(layers "B.Cu" "B.Mask" "B.Paste")
			(net "JTAG_RISER_N")
		)
		(zone
			(layer "B.Cu")
			(hatch none 0.5)
			(connect_pads
				(clearance 0)
			)
			(min_thickness 0.25)
			(keepout
				(tracks allowed)
				(vias not_allowed)
				(pads allowed)
				(copperpour not_allowed)
				(footprints allowed)
			)
			(placement
				(enabled no)
				(sheetname "")
			)
			(fill
				(thermal_gap 0.5)
				(thermal_bridge_width 0.5)
				(island_removal_mode 0)
			)
			(polygon
				(pts
					(xy 381.7366 -3.439414) (xy 381.7366 -2.931414) (xy 382.1176 -2.931414) (xy 382.1176 -3.439414)
				)
			)
		)
		(zone
			(layer "B.Cu")
			(hatch none 0.5)
			(connect_pads
				(clearance 0)
			)
			(min_thickness 0.25)
			(keepout
				(tracks not_allowed)
				(vias allowed)
				(pads allowed)
				(copperpour not_allowed)
				(footprints allowed)
			)
			(placement
				(enabled no)
				(sheetname "")
			)
			(fill
				(thermal_gap 0.5)
				(thermal_bridge_width 0.5)
				(island_removal_mode 0)
			)
			(polygon
				(pts
					(xy 382.1176 -3.439414) (xy 382.1176 -2.931414) (xy 381.7366 -2.931414) (xy 381.7366 -3.439414)
				)
			)
		)
	)
	(footprint ""
		(layer "B.Cu")
		(at 386.575808 -84.729828 180)
		(property "Reference" "R3P6"
			(at 0.8382 -0.67818 180)
			(unlocked yes)
			(layer "B.SilkS")
			(effects
				(font
					(size 0.4064 0.254)
					(thickness 0.1524)
				)
				(justify left mirror)
			)
		)
		(property "Value" ""
			(at 0 0 0)
			(layer "B.Fab")
			(effects
				(font
					(size 1.27 1.27)
				)
				(justify mirror)
			)
		)
		(duplicate_pad_numbers_are_jumpers no)
		(fp_poly
			(pts
				(xy 0.2794 -0.1016) (xy -0.2794 -0.1016) (xy -0.2794 0.9906) (xy 0.2794 0.9906)
			)
			(stroke
				(width 0)
				(type default)
			)
			(fill no)
			(layer "B.CrtYd")
		)
		(fp_line
			(start 0.2794 0.9906)
			(end -0.2794 0.9906)
			(stroke
				(width 0.1)
				(type default)
			)
			(layer "B.Fab")
		)
		(fp_line
			(start 0.2794 -0.1016)
			(end 0.2794 0.9906)
			(stroke
				(width 0.1)
				(type default)
			)
			(layer "B.Fab")
		)
		(fp_line
			(start -0.2794 0.9906)
			(end -0.2794 -0.1016)
			(stroke
				(width 0.1)
				(type default)
			)
			(layer "B.Fab")
		)
		(fp_line
			(start -0.2794 -0.1016)
			(end 0.2794 -0.1016)
			(stroke
				(width 0.1)
				(type default)
			)
			(layer "B.Fab")
		)
		(pad "1" smd rect
			(at 0 0)
			(size 0.508 0.508)
			(layers "B.Cu" "B.Mask" "B.Paste")
			(net "P1V05_PCH_STBY")
		)
		(pad "2" smd rect
			(at 0 0.889)
			(size 0.508 0.508)
			(layers "B.Cu" "B.Mask" "B.Paste")
			(net "FM_PRSNT_2_3_N")
		)
		(zone
			(layer "B.Cu")
			(hatch none 0.5)
			(connect_pads
				(clearance 0)
			)
			(min_thickness 0.25)
			(keepout
				(tracks not_allowed)
				(vias allowed)
				(pads allowed)
				(copperpour not_allowed)
				(footprints allowed)
			)
			(placement
				(enabled no)
				(sheetname "")
			)
			(fill
				(thermal_gap 0.5)
				(thermal_bridge_width 0.5)
				(island_removal_mode 0)
			)
			(polygon
				(pts
					(xy 386.321808 -85.364828) (xy 386.829808 -85.364828) (xy 386.829808 -84.983828) (xy 386.321808 -84.983828)
				)
			)
		)
		(zone
			(layer "B.Cu")
			(hatch none 0.5)
			(connect_pads
				(clearance 0)
			)
			(min_thickness 0.25)
			(keepout
				(tracks allowed)
				(vias not_allowed)
				(pads allowed)
				(copperpour not_allowed)
				(footprints allowed)
			)
			(placement
				(enabled no)
				(sheetname "")
			)
			(fill
				(thermal_gap 0.5)
				(thermal_bridge_width 0.5)
				(island_removal_mode 0)
			)
			(polygon
				(pts
					(xy 386.321808 -84.983828) (xy 386.829808 -84.983828) (xy 386.829808 -85.364828) (xy 386.321808 -85.364828)
				)
			)
		)
	)
	(footprint ""
		(layer "B.Cu")
		(at 426.0215 -11.684 -90)
		(property "Reference" "R2U47"
			(at 0 0 90)
			(layer "B.SilkS")
			(hide yes)
			(effects
				(font
					(size 1.27 1.27)
				)
				(justify mirror)
			)
		)
		(property "Value" ""
			(at 0 0 90)
			(layer "B.Fab")
			(effects
				(font
					(size 1.27 1.27)
				)
				(justify mirror)
			)
		)
		(duplicate_pad_numbers_are_jumpers no)
		(fp_poly
			(pts
				(xy 0.2794 -0.1016) (xy -0.2794 -0.1016) (xy -0.2794 0.9906) (xy 0.2794 0.9906)
			)
			(stroke
				(width 0)
				(type default)
			)
			(fill no)
			(layer "B.CrtYd")
		)
		(fp_line
			(start -0.2794 0.9906)
			(end -0.2794 -0.1016)
			(stroke
				(width 0.1)
				(type default)
			)
			(layer "B.Fab")
		)
		(fp_line
			(start 0.2794 0.9906)
			(end -0.2794 0.9906)
			(stroke
				(width 0.1)
				(type default)
			)
			(layer "B.Fab")
		)
		(fp_line
			(start -0.2794 -0.1016)
			(end 0.2794 -0.1016)
			(stroke
				(width 0.1)
				(type default)
			)
			(layer "B.Fab")
		)
		(fp_line
			(start 0.2794 -0.1016)
			(end 0.2794 0.9906)
			(stroke
				(width 0.1)
				(type default)
			)
			(layer "B.Fab")
		)
		(pad "1" smd rect
			(at 0 0 90)
			(size 0.508 0.508)
			(layers "B.Cu" "B.Mask" "B.Paste")
			(net "H_CPU0_MEMABC_MEMHOT_LVT3_N")
		)
		(pad "2" smd rect
			(at 0 0.889 90)
			(size 0.508 0.508)
			(layers "B.Cu" "B.Mask" "B.Paste")
			(net "H_CPU0_MEMABC_MEMHOT_LVT3_BMC_N")
		)
		(zone
			(layer "B.Cu")
			(hatch none 0.5)
			(connect_pads
				(clearance 0)
			)
			(min_thickness 0.25)
			(keepout
				(tracks not_allowed)
				(vias allowed)
				(pads allowed)
				(copperpour not_allowed)
				(footprints allowed)
			)
			(placement
				(enabled no)
				(sheetname "")
			)
			(fill
				(thermal_gap 0.5)
				(thermal_bridge_width 0.5)
				(island_removal_mode 0)
			)
			(polygon
				(pts
					(xy 425.3865 -11.43) (xy 425.3865 -11.938) (xy 425.7675 -11.938) (xy 425.7675 -11.43)
				)
			)
		)
		(zone
			(layer "B.Cu")
			(hatch none 0.5)
			(connect_pads
				(clearance 0)
			)
			(min_thickness 0.25)
			(keepout
				(tracks allowed)
				(vias not_allowed)
				(pads allowed)
				(copperpour not_allowed)
				(footprints allowed)
			)
			(placement
				(enabled no)
				(sheetname "")
			)
			(fill
				(thermal_gap 0.5)
				(thermal_bridge_width 0.5)
				(island_removal_mode 0)
			)
			(polygon
				(pts
					(xy 425.7675 -11.43) (xy 425.7675 -11.938) (xy 425.3865 -11.938) (xy 425.3865 -11.43)
				)
			)
		)
	)
)
